(kicad_pcb
	(version 20221018)
	(generator pcbnew)
	(general
    (thickness 1.656)
  )
	(paper "A4")
	(title_block
    (title "SDI-MIPI Bridge")
    (date "2023-08-09")
    (rev "1.3.4")
    (company "Antmicro")
		(comment 9 "footprints 155-164 of 190")
	)
	(layers
    (0 "F.Cu" signal)
    (1 "In1.Cu" power)
    (2 "In2.Cu" power)
    (3 "In3.Cu" signal)
    (4 "In4.Cu" signal)
    (31 "B.Cu" signal)
    (32 "B.Adhes" user "B.Adhesive")
    (33 "F.Adhes" user "F.Adhesive")
    (34 "B.Paste" user)
    (35 "F.Paste" user)
    (36 "B.SilkS" user "B.Silkscreen")
    (37 "F.SilkS" user "F.Silkscreen")
    (38 "B.Mask" user)
    (39 "F.Mask" user)
    (40 "Dwgs.User" user "User.Drawings")
    (41 "Cmts.User" user "User.Comments")
    (42 "Eco1.User" user "User.Eco1")
    (43 "Eco2.User" user "User.Eco2")
    (44 "Edge.Cuts" user)
    (45 "Margin" user)
    (46 "B.CrtYd" user "B.Courtyard")
    (47 "F.CrtYd" user "F.Courtyard")
    (48 "B.Fab" user)
    (49 "F.Fab" user)
  )
	(footprint "sdi-mipi-bridge-footprints:C_0402_1005Metric" (layer "B.Cu")
    (at 134.05 133.08)
    (descr "Capacitor SMD 0402")
    (tags "capacitor SMD 0402")
    (property "Author" "Antmicro")
    (property "Dielectric" "")
    (property "License" "Apache-2.0")
    (property "MPN" "C1005X6S1A105K050BC")
    (property "Manufacturer" "TDK")
    (property "Sheetfile" "sdi-mipi-bridge.kicad_sch")
    (property "Sheetname" "")
    (property "Val" "1u")
    (property "Voltage" "")
    (property "ki_description" " ")
    (attr smd)
    (fp_text reference "C25" (at 2.15 0.32) (layer "B.SilkS")
        (effects (font (size 0.7 0.7) (thickness 0.15)) (justify right bottom mirror))
    )
    (fp_text value "C_1u_0402" (at 100 -1.423) (layer "B.Fab") hide
        (effects (font (size 0.7 0.7) (thickness 0.15)) (justify right bottom mirror))
    )
    (fp_text user "Author: Antmicro" (at -0.932 -4.17) (layer "B.Fab") hide
        (effects (font (size 0.7 0.7) (thickness 0.15)) (justify right bottom mirror))
    )
    (fp_text user "${REFERENCE}" (at -0.932 -3.168) (layer "B.Fab") hide
        (effects (font (size 0.7 0.7) (thickness 0.15)) (justify right bottom mirror))
    )
    (fp_text user "License: Apache-2.0" (at -0.932 -5.17) (layer "B.Fab") hide
        (effects (font (size 0.7 0.7) (thickness 0.15)) (justify right bottom mirror))
    )
    (fp_rect (start -0.94 0.47) (end 0.94 -0.47)
      (stroke (width 0.05) (type solid)) (fill none) (layer "B.CrtYd"))
    (fp_rect (start -0.499 0.249) (end 0.499 -0.249)
      (stroke (width 0.15) (type solid)) (fill none) (layer "B.Fab"))
    (pad "1" smd roundrect (at -0.484 0) (size 0.59 0.64) (layers "B.Cu" "B.Paste" "B.Mask") (roundrect_rratio 0.25)
      (net 1 "GNDREF") (pintype "passive"))
    (pad "2" smd roundrect (at 0.484 0) (size 0.59 0.64) (layers "B.Cu" "B.Paste" "B.Mask") (roundrect_rratio 0.25)
      (net 2 "+1V2") (pintype "passive"))
  )
	(footprint "sdi-mipi-bridge-footprints:C_0402_1005Metric" (layer "B.Cu")
    (at 134.05 132.08)
    (descr "Capacitor SMD 0402")
    (tags "capacitor SMD 0402")
    (property "Author" "Antmicro")
    (property "Dielectric" "")
    (property "License" "Apache-2.0")
    (property "MPN" "C1005X6S1A105K050BC")
    (property "Manufacturer" "TDK")
    (property "Sheetfile" "sdi-mipi-bridge.kicad_sch")
    (property "Sheetname" "")
    (property "Val" "1u")
    (property "Voltage" "")
    (property "ki_description" " ")
    (attr smd)
    (fp_text reference "C29" (at 2.15 0.32) (layer "B.SilkS")
        (effects (font (size 0.7 0.7) (thickness 0.15)) (justify right bottom mirror))
    )
    (fp_text value "C_1u_0402" (at 100 -1.423) (layer "B.Fab") hide
        (effects (font (size 0.7 0.7) (thickness 0.15)) (justify right bottom mirror))
    )
    (fp_text user "Author: Antmicro" (at -0.932 -4.17) (layer "B.Fab") hide
        (effects (font (size 0.7 0.7) (thickness 0.15)) (justify right bottom mirror))
    )
    (fp_text user "${REFERENCE}" (at -0.932 -3.168) (layer "B.Fab") hide
        (effects (font (size 0.7 0.7) (thickness 0.15)) (justify right bottom mirror))
    )
    (fp_text user "License: Apache-2.0" (at -0.932 -5.17) (layer "B.Fab") hide
        (effects (font (size 0.7 0.7) (thickness 0.15)) (justify right bottom mirror))
    )
    (fp_rect (start -0.94 0.47) (end 0.94 -0.47)
      (stroke (width 0.05) (type solid)) (fill none) (layer "B.CrtYd"))
    (fp_rect (start -0.499 0.249) (end 0.499 -0.249)
      (stroke (width 0.15) (type solid)) (fill none) (layer "B.Fab"))
    (pad "1" smd roundrect (at -0.484 0) (size 0.59 0.64) (layers "B.Cu" "B.Paste" "B.Mask") (roundrect_rratio 0.25)
      (net 3 "GNDA") (pintype "passive"))
    (pad "2" smd roundrect (at 0.484 0) (size 0.59 0.64) (layers "B.Cu" "B.Paste" "B.Mask") (roundrect_rratio 0.25)
      (net 4 "VPP") (pintype "passive"))
  )
	(footprint "sdi-mipi-bridge-footprints:C_0402_1005Metric" (layer "B.Cu")
    (at 134.05 131.08)
    (descr "Capacitor SMD 0402")
    (tags "capacitor SMD 0402")
    (property "Author" "Antmicro")
    (property "Dielectric" "X7R")
    (property "License" "Apache-2.0")
    (property "MPN" "GRM155R71H103KA88D")
    (property "Manufacturer" "Murata")
    (property "Sheetfile" "sdi-mipi-bridge.kicad_sch")
    (property "Sheetname" "")
    (property "Val" "10n")
    (property "Voltage" "50V")
    (property "ki_description" " ")
    (attr smd)
    (fp_text reference "C33" (at 2.15 0.32) (layer "B.SilkS")
        (effects (font (size 0.7 0.7) (thickness 0.15)) (justify right bottom mirror))
    )
    (fp_text value "C_10n_0402" (at 100 -1.423) (layer "B.Fab") hide
        (effects (font (size 0.7 0.7) (thickness 0.15)) (justify right bottom mirror))
    )
    (fp_text user "Author: Antmicro" (at -0.932 -4.17) (layer "B.Fab") hide
        (effects (font (size 0.7 0.7) (thickness 0.15)) (justify right bottom mirror))
    )
    (fp_text user "${REFERENCE}" (at -0.932 -3.168) (layer "B.Fab") hide
        (effects (font (size 0.7 0.7) (thickness 0.15)) (justify right bottom mirror))
    )
    (fp_text user "License: Apache-2.0" (at -0.932 -5.17) (layer "B.Fab") hide
        (effects (font (size 0.7 0.7) (thickness 0.15)) (justify right bottom mirror))
    )
    (fp_rect (start -0.94 0.47) (end 0.94 -0.47)
      (stroke (width 0.05) (type solid)) (fill none) (layer "B.CrtYd"))
    (fp_rect (start -0.499 0.249) (end 0.499 -0.249)
      (stroke (width 0.15) (type solid)) (fill none) (layer "B.Fab"))
    (pad "1" smd roundrect (at -0.484 0) (size 0.59 0.64) (layers "B.Cu" "B.Paste" "B.Mask") (roundrect_rratio 0.25)
      (net 3 "GNDA") (pintype "passive"))
    (pad "2" smd roundrect (at 0.484 0) (size 0.59 0.64) (layers "B.Cu" "B.Paste" "B.Mask") (roundrect_rratio 0.25)
      (net 4 "VPP") (pintype "passive"))
  )
	(footprint "sdi-mipi-bridge-footprints:R_0402_1005Metric" (layer "B.Cu")
    (at 134.05 135.08 180)
    (descr "Resistor SMD 0402")
    (tags "resistor SMD 0402")
    (property "Author" "Antmicro")
    (property "License" "Apache-2.0")
    (property "MPN" "CR0402-FX-1203GLF")
    (property "Manufacturer" "Bourns")
    (property "Sheetfile" "sdi-mipi-bridge.kicad_sch")
    (property "Sheetname" "")
    (property "Tolerance" "1%")
    (property "Val" "120k")
    (property "ki_description" "120k resistor in 0402 package with 1% tolerance")
    (attr smd)
    (fp_text reference "R5" (at -4.35 -0.32) (layer "B.SilkS")
        (effects (font (size 0.7 0.7) (thickness 0.15)) (justify left bottom mirror))
    )
    (fp_text value "R_120k_0402" (at 0 -1.4) (layer "B.Fab") hide
        (effects (font (size 0.7 0.7) (thickness 0.15)) (justify left bottom mirror))
    )
    (fp_text user "${REFERENCE}" (at -0.95 -3.168) (layer "B.Fab") hide
        (effects (font (size 0.7 0.7) (thickness 0.15)) (justify left bottom mirror))
    )
    (fp_text user "Author: Antmicro" (at -0.95 -4.169) (layer "B.Fab") hide
        (effects (font (size 0.7 0.7) (thickness 0.15)) (justify left bottom mirror))
    )
    (fp_text user "License: Apache-2.0" (at -0.95 -5.169) (layer "B.Fab") hide
        (effects (font (size 0.7 0.7) (thickness 0.15)) (justify left bottom mirror))
    )
    (fp_rect (start -0.93 0.47) (end 0.93 -0.47)
      (stroke (width 0.05) (type solid)) (fill none) (layer "B.CrtYd"))
    (fp_rect (start -0.5 0.25) (end 0.5 -0.25)
      (stroke (width 0.15) (type solid)) (fill none) (layer "B.Fab"))
    (pad "1" smd roundrect (at -0.485 0 180) (size 0.59 0.64) (layers "B.Cu" "B.Paste" "B.Mask") (roundrect_rratio 0.25)
      (net 2 "+1V2") (pintype "passive"))
    (pad "2" smd roundrect (at 0.485 0 180) (size 0.59 0.64) (layers "B.Cu" "B.Paste" "B.Mask") (roundrect_rratio 0.25)
      (net 71 "Net-(U1-FB)") (pintype "passive"))
  )
	(footprint "sdi-mipi-bridge-footprints:R_0402_1005Metric" (layer "B.Cu")
    (at 134.05 136.08)
    (descr "Resistor SMD 0402")
    (tags "resistor SMD 0402")
    (property "Author" "Antmicro")
    (property "License" "Apache-2.0")
    (property "MPN" "CR0402-FX-1203GLF")
    (property "Manufacturer" "Bourns")
    (property "Sheetfile" "sdi-mipi-bridge.kicad_sch")
    (property "Sheetname" "")
    (property "Tolerance" "1%")
    (property "Val" "120k")
    (property "ki_description" "120k resistor in 0402 package with 1% tolerance")
    (attr smd)
    (fp_text reference "R6" (at 4.35 0.32) (layer "B.SilkS")
        (effects (font (size 0.7 0.7) (thickness 0.15)) (justify left bottom mirror))
    )
    (fp_text value "R_120k_0402" (at -100 -1.377) (layer "B.Fab") hide
        (effects (font (size 0.7 0.7) (thickness 0.15)) (justify right bottom mirror))
    )
    (fp_text user "${REFERENCE}" (at -0.95 -3.168) (layer "B.Fab") hide
        (effects (font (size 0.7 0.7) (thickness 0.15)) (justify right bottom mirror))
    )
    (fp_text user "Author: Antmicro" (at -0.95 -4.169) (layer "B.Fab") hide
        (effects (font (size 0.7 0.7) (thickness 0.15)) (justify right bottom mirror))
    )
    (fp_text user "License: Apache-2.0" (at -0.95 -5.169) (layer "B.Fab") hide
        (effects (font (size 0.7 0.7) (thickness 0.15)) (justify right bottom mirror))
    )
    (fp_rect (start -0.93 0.47) (end 0.93 -0.47)
      (stroke (width 0.05) (type solid)) (fill none) (layer "B.CrtYd"))
    (fp_rect (start -0.5 0.25) (end 0.5 -0.25)
      (stroke (width 0.15) (type solid)) (fill none) (layer "B.Fab"))
    (pad "1" smd roundrect (at -0.485 0) (size 0.59 0.64) (layers "B.Cu" "B.Paste" "B.Mask") (roundrect_rratio 0.25)
      (net 71 "Net-(U1-FB)") (pintype "passive"))
    (pad "2" smd roundrect (at 0.485 0) (size 0.59 0.64) (layers "B.Cu" "B.Paste" "B.Mask") (roundrect_rratio 0.25)
      (net 1 "GNDREF") (pintype "passive"))
  )
	(footprint "sdi-mipi-bridge-footprints:C_0402_1005Metric" (layer "B.Cu")
    (at 109.75 134.25 -90)
    (descr "Capacitor SMD 0402")
    (tags "capacitor SMD 0402")
    (property "Author" "Antmicro")
    (property "Dielectric" "X7R")
    (property "License" "Apache-2.0")
    (property "MPN" "GRM155R71H103KA88D")
    (property "Manufacturer" "Murata")
    (property "Sheetfile" "sdi-mipi-bridge.kicad_sch")
    (property "Sheetname" "")
    (property "Val" "10n")
    (property "Voltage" "50V")
    (property "ki_description" " ")
    (attr smd)
    (fp_text reference "C21" (at -3.65 -0.45 90) (layer "B.SilkS")
        (effects (font (size 0.7 0.7) (thickness 0.15)) (justify left bottom mirror))
    )
    (fp_text value "C_10n_0402" (at 0 -1.4 90) (layer "B.Fab") hide
        (effects (font (size 0.7 0.7) (thickness 0.15)) (justify left bottom mirror))
    )
    (fp_text user "${REFERENCE}" (at -0.932 -3.168 90) (layer "B.Fab") hide
        (effects (font (size 0.7 0.7) (thickness 0.15)) (justify left bottom mirror))
    )
    (fp_text user "Author: Antmicro" (at -0.932 -4.17 90) (layer "B.Fab") hide
        (effects (font (size 0.7 0.7) (thickness 0.15)) (justify left bottom mirror))
    )
    (fp_text user "License: Apache-2.0" (at -0.932 -5.17 90) (layer "B.Fab") hide
        (effects (font (size 0.7 0.7) (thickness 0.15)) (justify left bottom mirror))
    )
    (fp_rect (start -0.94 0.47) (end 0.94 -0.47)
      (stroke (width 0.05) (type solid)) (fill none) (layer "B.CrtYd"))
    (fp_rect (start -0.499 0.249) (end 0.499 -0.249)
      (stroke (width 0.15) (type solid)) (fill none) (layer "B.Fab"))
    (pad "1" smd roundrect (at -0.484 0 270) (size 0.59 0.64) (layers "B.Cu" "B.Paste" "B.Mask") (roundrect_rratio 0.25)
      (net 1 "GNDREF") (pintype "passive"))
    (pad "2" smd roundrect (at 0.484 0 270) (size 0.59 0.64) (layers "B.Cu" "B.Paste" "B.Mask") (roundrect_rratio 0.25)
      (net 6 "+3V3") (pintype "passive"))
  )
	(footprint "sdi-mipi-bridge-footprints:C_0402_1005Metric" (layer "B.Cu")
    (at 110.75 134.25 -90)
    (descr "Capacitor SMD 0402")
    (tags "capacitor SMD 0402")
    (property "Author" "Antmicro")
    (property "Dielectric" "")
    (property "License" "Apache-2.0")
    (property "MPN" "C1005X6S1A105K050BC")
    (property "Manufacturer" "TDK")
    (property "Sheetfile" "sdi-mipi-bridge.kicad_sch")
    (property "Sheetname" "")
    (property "Val" "1u")
    (property "Voltage" "")
    (property "ki_description" " ")
    (attr smd)
    (fp_text reference "C26" (at -3.65 -0.45 90) (layer "B.SilkS")
        (effects (font (size 0.7 0.7) (thickness 0.15)) (justify left bottom mirror))
    )
    (fp_text value "C_1u_0402" (at 0 -1.4 90) (layer "B.Fab") hide
        (effects (font (size 0.7 0.7) (thickness 0.15)) (justify left bottom mirror))
    )
    (fp_text user "Author: Antmicro" (at -0.932 -4.17 90) (layer "B.Fab") hide
        (effects (font (size 0.7 0.7) (thickness 0.15)) (justify left bottom mirror))
    )
    (fp_text user "${REFERENCE}" (at -0.932 -3.168 90) (layer "B.Fab") hide
        (effects (font (size 0.7 0.7) (thickness 0.15)) (justify left bottom mirror))
    )
    (fp_text user "License: Apache-2.0" (at -0.932 -5.17 90) (layer "B.Fab") hide
        (effects (font (size 0.7 0.7) (thickness 0.15)) (justify left bottom mirror))
    )
    (fp_rect (start -0.94 0.47) (end 0.94 -0.47)
      (stroke (width 0.05) (type solid)) (fill none) (layer "B.CrtYd"))
    (fp_rect (start -0.499 0.249) (end 0.499 -0.249)
      (stroke (width 0.15) (type solid)) (fill none) (layer "B.Fab"))
    (pad "1" smd roundrect (at -0.484 0 270) (size 0.59 0.64) (layers "B.Cu" "B.Paste" "B.Mask") (roundrect_rratio 0.25)
      (net 1 "GNDREF") (pintype "passive"))
    (pad "2" smd roundrect (at 0.484 0 270) (size 0.59 0.64) (layers "B.Cu" "B.Paste" "B.Mask") (roundrect_rratio 0.25)
      (net 6 "+3V3") (pintype "passive"))
  )
	(footprint "sdi-mipi-bridge-footprints:C_0402_1005Metric" (layer "B.Cu")
    (at 112.75 134.25 90)
    (descr "Capacitor SMD 0402")
    (tags "capacitor SMD 0402")
    (property "Author" "Antmicro")
    (property "Dielectric" "")
    (property "License" "Apache-2.0")
    (property "MPN" "C1005X6S1A105K050BC")
    (property "Manufacturer" "TDK")
    (property "Sheetfile" "sdi-mipi-bridge.kicad_sch")
    (property "Sheetname" "")
    (property "Val" "1u")
    (property "Voltage" "")
    (property "ki_description" " ")
    (attr smd)
    (fp_text reference "C30" (at 1.45 0.45 90) (layer "B.SilkS")
        (effects (font (size 0.7 0.7) (thickness 0.15)) (justify right bottom mirror))
    )
    (fp_text value "C_1u_0402" (at 0 -1.4 90) (layer "B.Fab") hide
        (effects (font (size 0.7 0.7) (thickness 0.15)) (justify right bottom mirror))
    )
    (fp_text user "Author: Antmicro" (at -0.932 -4.17 90) (layer "B.Fab") hide
        (effects (font (size 0.7 0.7) (thickness 0.15)) (justify right bottom mirror))
    )
    (fp_text user "${REFERENCE}" (at -0.932 -3.168 90) (layer "B.Fab") hide
        (effects (font (size 0.7 0.7) (thickness 0.15)) (justify right bottom mirror))
    )
    (fp_text user "License: Apache-2.0" (at -0.932 -5.17 90) (layer "B.Fab") hide
        (effects (font (size 0.7 0.7) (thickness 0.15)) (justify right bottom mirror))
    )
    (fp_rect (start -0.94 0.47) (end 0.94 -0.47)
      (stroke (width 0.05) (type solid)) (fill none) (layer "B.CrtYd"))
    (fp_rect (start -0.499 0.249) (end 0.499 -0.249)
      (stroke (width 0.15) (type solid)) (fill none) (layer "B.Fab"))
    (pad "1" smd roundrect (at -0.484 0 90) (size 0.59 0.64) (layers "B.Cu" "B.Paste" "B.Mask") (roundrect_rratio 0.25)
      (net 3 "GNDA") (pintype "passive"))
    (pad "2" smd roundrect (at 0.484 0 90) (size 0.59 0.64) (layers "B.Cu" "B.Paste" "B.Mask") (roundrect_rratio 0.25)
      (net 57 "VDD") (pintype "passive"))
  )
	(footprint "sdi-mipi-bridge-footprints:C_0402_1005Metric" (layer "B.Cu")
    (at 113.75 134.25 90)
    (descr "Capacitor SMD 0402")
    (tags "capacitor SMD 0402")
    (property "Author" "Antmicro")
    (property "Dielectric" "X7R")
    (property "License" "Apache-2.0")
    (property "MPN" "GRM155R71H103KA88D")
    (property "Manufacturer" "Murata")
    (property "Sheetfile" "sdi-mipi-bridge.kicad_sch")
    (property "Sheetname" "")
    (property "Val" "10n")
    (property "Voltage" "50V")
    (property "ki_description" " ")
    (attr smd)
    (fp_text reference "C34" (at 1.45 0.45 90) (layer "B.SilkS")
        (effects (font (size 0.7 0.7) (thickness 0.15)) (justify right bottom mirror))
    )
    (fp_text value "C_10n_0402" (at 0 -1.4 90) (layer "B.Fab") hide
        (effects (font (size 0.7 0.7) (thickness 0.15)) (justify right bottom mirror))
    )
    (fp_text user "${REFERENCE}" (at -0.932 -3.168 90) (layer "B.Fab") hide
        (effects (font (size 0.7 0.7) (thickness 0.15)) (justify right bottom mirror))
    )
    (fp_text user "Author: Antmicro" (at -0.932 -4.17 90) (layer "B.Fab") hide
        (effects (font (size 0.7 0.7) (thickness 0.15)) (justify right bottom mirror))
    )
    (fp_text user "License: Apache-2.0" (at -0.932 -5.17 90) (layer "B.Fab") hide
        (effects (font (size 0.7 0.7) (thickness 0.15)) (justify right bottom mirror))
    )
    (fp_rect (start -0.94 0.47) (end 0.94 -0.47)
      (stroke (width 0.05) (type solid)) (fill none) (layer "B.CrtYd"))
    (fp_rect (start -0.499 0.249) (end 0.499 -0.249)
      (stroke (width 0.15) (type solid)) (fill none) (layer "B.Fab"))
    (pad "1" smd roundrect (at -0.484 0 90) (size 0.59 0.64) (layers "B.Cu" "B.Paste" "B.Mask") (roundrect_rratio 0.25)
      (net 3 "GNDA") (pintype "passive"))
    (pad "2" smd roundrect (at 0.484 0 90) (size 0.59 0.64) (layers "B.Cu" "B.Paste" "B.Mask") (roundrect_rratio 0.25)
      (net 57 "VDD") (pintype "passive"))
  )
	(footprint "sdi-mipi-bridge-footprints:R_0402_1005Metric" (layer "B.Cu")
    (at 113.96 119.41 -90)
    (descr "Resistor SMD 0402")
    (tags "resistor SMD 0402")
    (property "Author" "Antmicro")
    (property "License" "Apache-2.0")
    (property "MPN" "CR0402-FX-7500GLF")
    (property "Manufacturer" "Bourns")
    (property "Sheetfile" "sdi-mipi-bridge.kicad_sch")
    (property "Sheetname" "")
    (property "Tolerance" "1%")
    (property "Val" "750R")
    (property "ki_description" "750R resistor in 0402 package with 1% tolerance")
    (attr smd)
    (fp_text reference "R4" (at -0.81 0.76 90) (layer "B.SilkS")
        (effects (font (size 0.7 0.7) (thickness 0.15)) (justify left bottom mirror))
    )
    (fp_text value "R_750R_0402" (at 0 -1.4 90) (layer "B.Fab") hide
        (effects (font (size 0.7 0.7) (thickness 0.15)) (justify left bottom mirror))
    )
    (fp_text user "Author: Antmicro" (at -0.95 -4.169 90) (layer "B.Fab") hide
        (effects (font (size 0.7 0.7) (thickness 0.15)) (justify left bottom mirror))
    )
    (fp_text user "License: Apache-2.0" (at -0.95 -5.169 90) (layer "B.Fab") hide
        (effects (font (size 0.7 0.7) (thickness 0.15)) (justify left bottom mirror))
    )
    (fp_text user "${REFERENCE}" (at -0.95 -3.168 90) (layer "B.Fab") hide
        (effects (font (size 0.7 0.7) (thickness 0.15)) (justify left bottom mirror))
    )
    (fp_rect (start -0.93 0.47) (end 0.93 -0.47)
      (stroke (width 0.05) (type solid)) (fill none) (layer "B.CrtYd"))
    (fp_rect (start -0.5 0.25) (end 0.5 -0.25)
      (stroke (width 0.15) (type solid)) (fill none) (layer "B.Fab"))
    (pad "1" smd roundrect (at -0.485 0 270) (size 0.59 0.64) (layers "B.Cu" "B.Paste" "B.Mask") (roundrect_rratio 0.25)
      (net 57 "VDD") (pintype "passive"))
    (pad "2" smd roundrect (at 0.485 0 270) (size 0.59 0.64) (layers "B.Cu" "B.Paste" "B.Mask") (roundrect_rratio 0.25)
      (net 67 "Net-(U3-RSET)") (pintype "passive"))
  )
)
